(kicad_pcb
	(version 20260206)
	(generator "pcbnew")
	(generator_version "10.0")
	(general
		(thickness 1.6)
		(legacy_teardrops no)
	)
	(paper "A4")
	(title_block
		(title "04192023_DAF0TMB3IC0_F0TG_MB_C_brd_V02_OCP.brd")
		(comment 1 "Grand Teton / footprint 2417 of 8354 (U6015), pads 1-111 of 354")
	)
	(layers
		(0 "F.Cu" signal "TOP")
		(4 "In1.Cu" signal "GND")
		(6 "In2.Cu" signal "IN1")
		(8 "In3.Cu" signal "GND1")
		(10 "In4.Cu" signal "IN2")
		(12 "In5.Cu" signal "GND2")
		(14 "In6.Cu" signal "IN3")
		(16 "In7.Cu" signal "GND3")
		(18 "In8.Cu" signal "VCC")
		(20 "In9.Cu" signal "VCC1")
		(22 "In10.Cu" signal "GND4")
		(24 "In11.Cu" signal "IN4")
		(26 "In12.Cu" signal "GND5")
		(28 "In13.Cu" signal "IN5")
		(30 "In14.Cu" signal "GND6")
		(32 "In15.Cu" signal "IN6")
		(34 "In16.Cu" signal "GND7")
		(2 "B.Cu" signal "BOTTOM")
		(9 "F.Adhes" user "F.Adhesive")
		(11 "B.Adhes" user "B.Adhesive")
		(13 "F.Paste" user "Package Geometry/Pastemask Top")
		(15 "B.Paste" user "Package Geometry/Pastemask Bottom")
		(5 "F.SilkS" user "Ref Des/Silkscreen Top")
		(7 "B.SilkS" user "Ref Des/Silkscreen Bottom")
		(1 "F.Mask" user "Board Geometry/Soldermask Top")
		(3 "B.Mask" user "Board Geometry/Soldermask Bottom")
		(17 "Dwgs.User" user "User.Drawings")
		(19 "Cmts.User" user "User.Comments")
		(21 "Eco1.User" user "User.Eco1")
		(23 "Eco2.User" user "User.Eco2")
		(25 "Edge.Cuts" user "Board Geometry/Outline")
		(27 "Margin" user)
		(31 "F.CrtYd" user "Package Geometry/Place Bound Top")
		(29 "B.CrtYd" user "Package Geometry/Place Bound Bottom")
		(35 "F.Fab" user "Ref Des/Assembly Top")
		(33 "B.Fab" user "Ref Des/Assembly Bottom")
	)
	(footprint ""
		(layer "F.Cu")
		(at 88.995758 -387.342634)
		(property "Reference" "U6015"
			(at -7.723124 -7.528052 0)
			(unlocked yes)
			(layer "F.SilkS")
			(effects
				(font
					(size 0.7874 0.5842)
					(thickness 0.1524)
				)
				(justify left)
			)
		)
		(property "Value" ""
			(at 0 0 0)
			(layer "F.Fab")
			(effects
				(font
					(size 1.27 1.27)
				)
			)
		)
		(duplicate_pad_numbers_are_jumpers no)
		(pad "A1" smd oval
			(at 11.050016 -3.938524)
			(size 0.254 0.3302)
			(layers "F.Cu" "F.Mask" "F.Paste")
			(net "NCF_A1_CPU1_P1_GND")
		)
		(pad "A35" smd oval
			(at 11.050016 3.940048)
			(size 0.254 0.3302)
			(layers "F.Cu" "F.Mask" "F.Paste")
			(net "NCF_CPU1_P1_GND")
		)
		(pad "AA10" smd circle
			(at 7.602728 -1.431798)
			(size 0.381 0.381)
			(layers "F.Cu" "F.Mask" "F.Paste")
			(net "P5E_CPU1_P1_TX_BUF_DN<14>")
		)
		(pad "AA29" smd circle
			(at 7.602728 2.032254)
			(size 0.381 0.381)
			(layers "F.Cu" "F.Mask" "F.Paste")
			(net "P5E_CPU1_P1_RX_DN<14>")
		)
		(pad "AB1" smd oval
			(at 7.450074 -3.938524)
			(size 0.254 0.3302)
			(layers "F.Cu" "F.Mask" "F.Paste")
			(net "P5E_CPU1_P1_RX_BUF_DP<14>")
		)
		(pad "AB35" smd oval
			(at 7.450074 3.940048)
			(size 0.254 0.3302)
			(layers "F.Cu" "F.Mask" "F.Paste")
			(net "P5E_CPU1_P1_TX_C_DN<14>")
		)
		(pad "AC4" smd circle
			(at 7.202678 -2.817368)
			(size 0.381 0.381)
			(layers "F.Cu" "F.Mask" "F.Paste")
			(net "GND")
		)
		(pad "AC13" smd circle
			(at 7.202678 -0.79629)
			(size 0.3048 0.3048)
			(layers "F.Cu" "F.Mask" "F.Paste")
			(net "GND")
		)
		(pad "AC17" smd circle
			(at 7.202678 -0.296164)
			(size 0.3048 0.3048)
			(layers "F.Cu" "F.Mask" "F.Paste")
			(net "P0V9_CPU1_RT1_2A")
		)
		(pad "AC20" smd circle
			(at 7.202678 0.203708)
			(size 0.3048 0.3048)
			(layers "F.Cu" "F.Mask" "F.Paste")
			(net "P0V9_CPU1_RT1_2A")
		)
		(pad "AC22" smd circle
			(at 7.202678 0.703834)
			(size 0.3048 0.3048)
			(layers "F.Cu" "F.Mask" "F.Paste")
			(net "GND")
		)
		(pad "AC32" smd circle
			(at 7.202678 2.724912)
			(size 0.381 0.381)
			(layers "F.Cu" "F.Mask" "F.Paste")
			(net "GND")
		)
		(pad "AD2" smd circle
			(at 7.1501 -3.41884)
			(size 0.3048 0.3048)
			(layers "F.Cu" "F.Mask" "F.Paste")
			(net "GND")
		)
		(pad "AD34" smd circle
			(at 7.1501 3.420364)
			(size 0.3048 0.3048)
			(layers "F.Cu" "F.Mask" "F.Paste")
			(net "GND")
		)
		(pad "AE1" smd oval
			(at 6.849872 -3.938524)
			(size 0.254 0.3302)
			(layers "F.Cu" "F.Mask" "F.Paste")
			(net "GND")
		)
		(pad "AE35" smd oval
			(at 6.849872 3.940048)
			(size 0.254 0.3302)
			(layers "F.Cu" "F.Mask" "F.Paste")
			(net "GND")
		)
		(pad "AF7" smd circle
			(at 6.802628 -2.12471)
			(size 0.381 0.381)
			(layers "F.Cu" "F.Mask" "F.Paste")
			(net "P5E_CPU1_P1_TX_BUF_DP<13>")
		)
		(pad "AF26" smd circle
			(at 6.802628 1.339342)
			(size 0.381 0.381)
			(layers "F.Cu" "F.Mask" "F.Paste")
			(net "P5E_CPU1_P1_RX_DP<13>")
		)
		(pad "AG2" smd circle
			(at 6.549898 -3.41884)
			(size 0.3048 0.3048)
			(layers "F.Cu" "F.Mask" "F.Paste")
			(net "P5E_CPU1_P1_RX_BUF_DN<13>")
		)
		(pad "AG34" smd circle
			(at 6.549898 3.420364)
			(size 0.3048 0.3048)
			(layers "F.Cu" "F.Mask" "F.Paste")
			(net "P5E_CPU1_P1_TX_C_DN<13>")
		)
		(pad "AH10" smd circle
			(at 6.402578 -1.431798)
			(size 0.381 0.381)
			(layers "F.Cu" "F.Mask" "F.Paste")
			(net "P5E_CPU1_P1_TX_BUF_DN<13>")
		)
		(pad "AH29" smd circle
			(at 6.402578 2.032254)
			(size 0.381 0.381)
			(layers "F.Cu" "F.Mask" "F.Paste")
			(net "P5E_CPU1_P1_RX_DN<13>")
		)
		(pad "AJ1" smd oval
			(at 6.249924 -3.938524)
			(size 0.254 0.3302)
			(layers "F.Cu" "F.Mask" "F.Paste")
			(net "P5E_CPU1_P1_RX_BUF_DP<13>")
		)
		(pad "AJ35" smd oval
			(at 6.249924 3.940048)
			(size 0.254 0.3302)
			(layers "F.Cu" "F.Mask" "F.Paste")
			(net "P5E_CPU1_P1_TX_C_DP<13>")
		)
		(pad "AK4" smd circle
			(at 6.002528 -2.817368)
			(size 0.381 0.381)
			(layers "F.Cu" "F.Mask" "F.Paste")
			(net "GND")
		)
		(pad "AK13" smd circle
			(at 6.002528 -0.79629)
			(size 0.3048 0.3048)
			(layers "F.Cu" "F.Mask" "F.Paste")
			(net "GND")
		)
		(pad "AK17" smd circle
			(at 6.002528 -0.296164)
			(size 0.3048 0.3048)
			(layers "F.Cu" "F.Mask" "F.Paste")
			(net "P0V9_CPU1_RT1_2A")
		)
		(pad "AK20" smd circle
			(at 6.002528 0.203708)
			(size 0.3048 0.3048)
			(layers "F.Cu" "F.Mask" "F.Paste")
			(net "P0V9_CPU1_RT1_2A")
		)
		(pad "AK22" smd circle
			(at 6.002528 0.703834)
			(size 0.3048 0.3048)
			(layers "F.Cu" "F.Mask" "F.Paste")
			(net "GND")
		)
		(pad "AK32" smd circle
			(at 6.002528 2.724912)
			(size 0.381 0.381)
			(layers "F.Cu" "F.Mask" "F.Paste")
			(net "GND")
		)
		(pad "AL2" smd circle
			(at 5.94995 -3.41884)
			(size 0.3048 0.3048)
			(layers "F.Cu" "F.Mask" "F.Paste")
			(net "GND")
		)
		(pad "AL34" smd circle
			(at 5.94995 3.420364)
			(size 0.3048 0.3048)
			(layers "F.Cu" "F.Mask" "F.Paste")
			(net "GND")
		)
		(pad "AM1" smd oval
			(at 5.649976 -3.938524)
			(size 0.254 0.3302)
			(layers "F.Cu" "F.Mask" "F.Paste")
			(net "GND")
		)
		(pad "AM35" smd oval
			(at 5.649976 3.940048)
			(size 0.254 0.3302)
			(layers "F.Cu" "F.Mask" "F.Paste")
			(net "GND")
		)
		(pad "AN7" smd circle
			(at 5.602478 -2.12471)
			(size 0.381 0.381)
			(layers "F.Cu" "F.Mask" "F.Paste")
			(net "P5E_CPU1_P1_TX_BUF_DP<12>")
		)
		(pad "AN26" smd circle
			(at 5.602478 1.339342)
			(size 0.381 0.381)
			(layers "F.Cu" "F.Mask" "F.Paste")
			(net "P5E_CPU1_P1_RX_DP<12>")
		)
		(pad "AP2" smd circle
			(at 5.350002 -3.41884)
			(size 0.3048 0.3048)
			(layers "F.Cu" "F.Mask" "F.Paste")
			(net "P5E_CPU1_P1_RX_BUF_DN<12>")
		)
		(pad "AP34" smd circle
			(at 5.350002 3.420364)
			(size 0.3048 0.3048)
			(layers "F.Cu" "F.Mask" "F.Paste")
			(net "P5E_CPU1_P1_TX_C_DN<12>")
		)
		(pad "AR10" smd circle
			(at 5.202682 -1.431798)
			(size 0.381 0.381)
			(layers "F.Cu" "F.Mask" "F.Paste")
			(net "P5E_CPU1_P1_TX_BUF_DN<12>")
		)
		(pad "AR29" smd circle
			(at 5.202682 2.032254)
			(size 0.381 0.381)
			(layers "F.Cu" "F.Mask" "F.Paste")
			(net "P5E_CPU1_P1_RX_DN<12>")
		)
		(pad "AT1" smd oval
			(at 5.050028 -3.938524)
			(size 0.254 0.3302)
			(layers "F.Cu" "F.Mask" "F.Paste")
			(net "P5E_CPU1_P1_RX_BUF_DP<12>")
		)
		(pad "AT35" smd oval
			(at 5.050028 3.940048)
			(size 0.254 0.3302)
			(layers "F.Cu" "F.Mask" "F.Paste")
			(net "P5E_CPU1_P1_TX_C_DP<12>")
		)
		(pad "AU4" smd circle
			(at 4.802632 -2.817368)
			(size 0.381 0.381)
			(layers "F.Cu" "F.Mask" "F.Paste")
			(net "GND")
		)
		(pad "AU13" smd circle
			(at 4.802632 -0.79629)
			(size 0.3048 0.3048)
			(layers "F.Cu" "F.Mask" "F.Paste")
			(net "GND")
		)
		(pad "AU17" smd circle
			(at 4.802632 -0.296164)
			(size 0.3048 0.3048)
			(layers "F.Cu" "F.Mask" "F.Paste")
			(net "P0V9_CPU1_RT1_2A")
		)
		(pad "AU20" smd circle
			(at 4.802632 0.203708)
			(size 0.3048 0.3048)
			(layers "F.Cu" "F.Mask" "F.Paste")
			(net "P0V9_CPU1_RT1_2A")
		)
		(pad "AU22" smd circle
			(at 4.802632 0.703834)
			(size 0.3048 0.3048)
			(layers "F.Cu" "F.Mask" "F.Paste")
			(net "GND")
		)
		(pad "AU32" smd circle
			(at 4.802632 2.724912)
			(size 0.381 0.381)
			(layers "F.Cu" "F.Mask" "F.Paste")
			(net "GND")
		)
		(pad "AV2" smd circle
			(at 4.750054 -3.41884)
			(size 0.3048 0.3048)
			(layers "F.Cu" "F.Mask" "F.Paste")
			(net "GND")
		)
		(pad "AV34" smd circle
			(at 4.750054 3.420364)
			(size 0.3048 0.3048)
			(layers "F.Cu" "F.Mask" "F.Paste")
			(net "GND")
		)
		(pad "AW1" smd oval
			(at 4.45008 -3.938524)
			(size 0.254 0.3302)
			(layers "F.Cu" "F.Mask" "F.Paste")
			(net "GND")
		)
		(pad "AW35" smd oval
			(at 4.45008 3.940048)
			(size 0.254 0.3302)
			(layers "F.Cu" "F.Mask" "F.Paste")
			(net "GND")
		)
		(pad "AY7" smd circle
			(at 4.402582 -2.12471)
			(size 0.381 0.381)
			(layers "F.Cu" "F.Mask" "F.Paste")
			(net "P5E_CPU1_P1_TX_BUF_DP<11>")
		)
		(pad "AY26" smd circle
			(at 4.402582 1.339342)
			(size 0.381 0.381)
			(layers "F.Cu" "F.Mask" "F.Paste")
			(net "P5E_CPU1_P1_RX_DP<11>")
		)
		(pad "B3" smd oval
			(at 10.885932 -2.888488 90)
			(size 0.254 0.3302)
			(layers "F.Cu" "F.Mask" "F.Paste")
			(net "JTAG_TCK_RT_CPU1_P1")
		)
		(pad "B6" smd oval
			(at 10.885932 -2.288286 90)
			(size 0.254 0.3302)
			(layers "F.Cu" "F.Mask" "F.Paste")
			(net "JTAG_TDI_RT_CPU1_P1")
		)
		(pad "B9" smd oval
			(at 10.885932 -1.688338 90)
			(size 0.254 0.3302)
			(layers "F.Cu" "F.Mask" "F.Paste")
			(net "JTAG_TDO_RT_CPU1_P1")
		)
		(pad "B12" smd oval
			(at 10.885932 -1.08839 90)
			(size 0.254 0.3302)
			(layers "F.Cu" "F.Mask" "F.Paste")
			(net "JTAG_TMS_RT_CPU1_P1")
		)
		(pad "B16" smd oval
			(at 10.885932 -0.488442 90)
			(size 0.254 0.3302)
			(layers "F.Cu" "F.Mask" "F.Paste")
			(net "Net_2221")
		)
		(pad "B19" smd oval
			(at 10.885932 0.111506 90)
			(size 0.254 0.3302)
			(layers "F.Cu" "F.Mask" "F.Paste")
			(net "GND")
		)
		(pad "B23" smd oval
			(at 10.885932 0.711708 90)
			(size 0.254 0.3302)
			(layers "F.Cu" "F.Mask" "F.Paste")
			(net "RT_CPU1_P1_ADDR2")
		)
		(pad "B25" smd oval
			(at 10.885932 1.311656 90)
			(size 0.254 0.3302)
			(layers "F.Cu" "F.Mask" "F.Paste")
			(net "RT_CPU1_P1_ADDR3")
		)
		(pad "B28" smd oval
			(at 10.885932 1.911604 90)
			(size 0.254 0.3302)
			(layers "F.Cu" "F.Mask" "F.Paste")
			(net "SMB_RT_CPU1_P1_R2_SDA")
		)
		(pad "B31" smd oval
			(at 10.885932 2.511552 90)
			(size 0.254 0.3302)
			(layers "F.Cu" "F.Mask" "F.Paste")
			(net "SMB_RT_CPU1_P1_R2_SCL")
		)
		(pad "BA2" smd circle
			(at 4.150106 -3.41884)
			(size 0.3048 0.3048)
			(layers "F.Cu" "F.Mask" "F.Paste")
			(net "P5E_CPU1_P1_RX_BUF_DN<11>")
		)
		(pad "BA34" smd circle
			(at 4.150106 3.420364)
			(size 0.3048 0.3048)
			(layers "F.Cu" "F.Mask" "F.Paste")
			(net "P5E_CPU1_P1_TX_C_DN<11>")
		)
		(pad "BB10" smd circle
			(at 4.002532 -1.431798)
			(size 0.381 0.381)
			(layers "F.Cu" "F.Mask" "F.Paste")
			(net "P5E_CPU1_P1_TX_BUF_DN<11>")
		)
		(pad "BB29" smd circle
			(at 4.002532 2.032254)
			(size 0.381 0.381)
			(layers "F.Cu" "F.Mask" "F.Paste")
			(net "P5E_CPU1_P1_RX_DN<11>")
		)
		(pad "BC1" smd oval
			(at 3.849878 -3.938524)
			(size 0.254 0.3302)
			(layers "F.Cu" "F.Mask" "F.Paste")
			(net "P5E_CPU1_P1_RX_BUF_DP<11>")
		)
		(pad "BC35" smd oval
			(at 3.849878 3.940048)
			(size 0.254 0.3302)
			(layers "F.Cu" "F.Mask" "F.Paste")
			(net "P5E_CPU1_P1_TX_C_DP<11>")
		)
		(pad "BD4" smd circle
			(at 3.602482 -2.817368)
			(size 0.381 0.381)
			(layers "F.Cu" "F.Mask" "F.Paste")
			(net "GND")
		)
		(pad "BD13" smd circle
			(at 3.602482 -0.79629)
			(size 0.3048 0.3048)
			(layers "F.Cu" "F.Mask" "F.Paste")
			(net "GND")
		)
		(pad "BD17" smd circle
			(at 3.602482 -0.296164)
			(size 0.3048 0.3048)
			(layers "F.Cu" "F.Mask" "F.Paste")
			(net "P0V9_CPU1_RT1_2A_2D")
		)
		(pad "BD20" smd circle
			(at 3.602482 0.203708)
			(size 0.3048 0.3048)
			(layers "F.Cu" "F.Mask" "F.Paste")
			(net "P0V9_CPU1_RT1_2A_2D")
		)
		(pad "BD22" smd circle
			(at 3.602482 0.703834)
			(size 0.3048 0.3048)
			(layers "F.Cu" "F.Mask" "F.Paste")
			(net "GND")
		)
		(pad "BD32" smd circle
			(at 3.602482 2.724912)
			(size 0.381 0.381)
			(layers "F.Cu" "F.Mask" "F.Paste")
			(net "GND")
		)
		(pad "BE2" smd circle
			(at 3.549904 -3.41884)
			(size 0.3048 0.3048)
			(layers "F.Cu" "F.Mask" "F.Paste")
			(net "GND")
		)
		(pad "BE34" smd circle
			(at 3.549904 3.420364)
			(size 0.3048 0.3048)
			(layers "F.Cu" "F.Mask" "F.Paste")
			(net "GND")
		)
		(pad "BF1" smd oval
			(at 3.24993 -3.938524)
			(size 0.254 0.3302)
			(layers "F.Cu" "F.Mask" "F.Paste")
			(net "GND")
		)
		(pad "BF35" smd oval
			(at 3.24993 3.940048)
			(size 0.254 0.3302)
			(layers "F.Cu" "F.Mask" "F.Paste")
			(net "GND")
		)
		(pad "BG7" smd circle
			(at 3.202686 -2.12471)
			(size 0.381 0.381)
			(layers "F.Cu" "F.Mask" "F.Paste")
			(net "P5E_CPU1_P1_TX_BUF_DP<10>")
		)
		(pad "BG26" smd circle
			(at 3.202686 1.339342)
			(size 0.381 0.381)
			(layers "F.Cu" "F.Mask" "F.Paste")
			(net "P5E_CPU1_P1_RX_DP<10>")
		)
		(pad "BH2" smd circle
			(at 2.949956 -3.41884)
			(size 0.3048 0.3048)
			(layers "F.Cu" "F.Mask" "F.Paste")
			(net "P5E_CPU1_P1_RX_BUF_DN<10>")
		)
		(pad "BH34" smd circle
			(at 2.949956 3.420364)
			(size 0.3048 0.3048)
			(layers "F.Cu" "F.Mask" "F.Paste")
			(net "P5E_CPU1_P1_TX_C_DN<10>")
		)
		(pad "BJ10" smd circle
			(at 2.802636 -1.431798)
			(size 0.381 0.381)
			(layers "F.Cu" "F.Mask" "F.Paste")
			(net "P5E_CPU1_P1_TX_BUF_DN<10>")
		)
		(pad "BJ29" smd circle
			(at 2.802636 2.032254)
			(size 0.381 0.381)
			(layers "F.Cu" "F.Mask" "F.Paste")
			(net "P5E_CPU1_P1_RX_DN<10>")
		)
		(pad "BK1" smd oval
			(at 2.649982 -3.938524)
			(size 0.254 0.3302)
			(layers "F.Cu" "F.Mask" "F.Paste")
			(net "P5E_CPU1_P1_RX_BUF_DP<10>")
		)
		(pad "BK35" smd oval
			(at 2.649982 3.940048)
			(size 0.254 0.3302)
			(layers "F.Cu" "F.Mask" "F.Paste")
			(net "P5E_CPU1_P1_TX_C_DP<10>")
		)
		(pad "BL4" smd circle
			(at 2.402586 -2.817368)
			(size 0.381 0.381)
			(layers "F.Cu" "F.Mask" "F.Paste")
			(net "GND")
		)
		(pad "BL13" smd circle
			(at 2.402586 -0.79629)
			(size 0.3048 0.3048)
			(layers "F.Cu" "F.Mask" "F.Paste")
			(net "GND")
		)
		(pad "BL17" smd circle
			(at 2.402586 -0.296164)
			(size 0.3048 0.3048)
			(layers "F.Cu" "F.Mask" "F.Paste")
			(net "P0V9_CPU1_RT_2D")
		)
		(pad "BL20" smd circle
			(at 2.402586 0.203708)
			(size 0.3048 0.3048)
			(layers "F.Cu" "F.Mask" "F.Paste")
			(net "P0V9_CPU1_RT_2D")
		)
		(pad "BL22" smd circle
			(at 2.402586 0.703834)
			(size 0.3048 0.3048)
			(layers "F.Cu" "F.Mask" "F.Paste")
			(net "GND")
		)
		(pad "BL32" smd circle
			(at 2.402586 2.724912)
			(size 0.381 0.381)
			(layers "F.Cu" "F.Mask" "F.Paste")
			(net "GND")
		)
		(pad "BM2" smd circle
			(at 2.350008 -3.41884)
			(size 0.3048 0.3048)
			(layers "F.Cu" "F.Mask" "F.Paste")
			(net "GND")
		)
		(pad "BM34" smd circle
			(at 2.350008 3.420364)
			(size 0.3048 0.3048)
			(layers "F.Cu" "F.Mask" "F.Paste")
			(net "GND")
		)
		(pad "BN1" smd oval
			(at 2.050034 -3.938524)
			(size 0.254 0.3302)
			(layers "F.Cu" "F.Mask" "F.Paste")
			(net "GND")
		)
		(pad "BN35" smd oval
			(at 2.050034 3.940048)
			(size 0.254 0.3302)
			(layers "F.Cu" "F.Mask" "F.Paste")
			(net "GND")
		)
		(pad "BP7" smd circle
			(at 2.002536 -2.12471)
			(size 0.381 0.381)
			(layers "F.Cu" "F.Mask" "F.Paste")
			(net "P5E_CPU1_P1_TX_BUF_DP<9>")
		)
		(pad "BP26" smd circle
			(at 2.002536 1.339342)
			(size 0.381 0.381)
			(layers "F.Cu" "F.Mask" "F.Paste")
			(net "P5E_CPU1_P1_RX_DP<9>")
		)
		(pad "BR2" smd circle
			(at 1.75006 -3.41884)
			(size 0.3048 0.3048)
			(layers "F.Cu" "F.Mask" "F.Paste")
			(net "P5E_CPU1_P1_RX_BUF_DN<9>")
		)
		(pad "BR34" smd circle
			(at 1.75006 3.420364)
			(size 0.3048 0.3048)
			(layers "F.Cu" "F.Mask" "F.Paste")
			(net "P5E_CPU1_P1_TX_C_DN<9>")
		)
		(pad "BT10" smd circle
			(at 1.602486 -1.431798)
			(size 0.381 0.381)
			(layers "F.Cu" "F.Mask" "F.Paste")
			(net "P5E_CPU1_P1_TX_BUF_DN<9>")
		)
		(pad "BT29" smd circle
			(at 1.602486 2.032254)
			(size 0.381 0.381)
			(layers "F.Cu" "F.Mask" "F.Paste")
			(net "P5E_CPU1_P1_RX_DN<9>")
		)
		(pad "BU1" smd oval
			(at 1.450086 -3.938524)
			(size 0.254 0.3302)
			(layers "F.Cu" "F.Mask" "F.Paste")
			(net "P5E_CPU1_P1_RX_BUF_DP<9>")
		)
		(pad "BU35" smd oval
			(at 1.450086 3.940048)
			(size 0.254 0.3302)
			(layers "F.Cu" "F.Mask" "F.Paste")
			(net "P5E_CPU1_P1_TX_C_DP<9>")
		)
		(pad "BV4" smd circle
			(at 1.20269 -2.817368)
			(size 0.381 0.381)
			(layers "F.Cu" "F.Mask" "F.Paste")
			(net "GND")
		)
		(pad "BV13" smd circle
			(at 1.20269 -0.79629)
			(size 0.3048 0.3048)
			(layers "F.Cu" "F.Mask" "F.Paste")
			(net "GND")
		)
		(pad "BV17" smd circle
			(at 1.20269 -0.296164)
			(size 0.3048 0.3048)
			(layers "F.Cu" "F.Mask" "F.Paste")
			(net "P1V8_CPU1_RT1_1A_1D")
		)
		(pad "BV20" smd circle
			(at 1.20269 0.203708)
			(size 0.3048 0.3048)
			(layers "F.Cu" "F.Mask" "F.Paste")
			(net "P1V8_CPU1_RT1_1A")
		)
		(pad "BV22" smd circle
			(at 1.20269 0.703834)
			(size 0.3048 0.3048)
			(layers "F.Cu" "F.Mask" "F.Paste")
			(net "GND")
		)
	)
)
